# S9S_MB_2U (Grand Teton) — schematic netlist excerpt (pin names and nets, part order shuffled) for the footprints in the layout excerpt that follows; sources: Cadence DE-HDL packaged netlist, KiCad conversion of 03242023_DA0F0TMBIJ0_F0T_Motherboard_J_brd_V01_OCP.brd

R4679  Q_RES  10K 1% CHIP  pkg 0402LF  page 260 : A = P5V ; B = PWRGD_P5V
R340  Q_RES  0 5% CHIP  pkg 0402LF  page 225 : A = H_CPU0_ERR1_LVC1_R_N ; B = H_CPU_ERR1_LVC1_R_N

(kicad_pcb
	(version 20260206)
	(generator "pcbnew")
	(generator_version "10.0")
	(general
		(thickness 1.6)
		(legacy_teardrops no)
	)
	(paper "A4")
	(title_block
		(title "03242023_DA0F0TMBIJ0_F0T_Motherboard_J_brd_V01_OCP.brd")
		(comment 1 "Grand Teton / footprints 5461-5462 of 6105")
	)
	(layers
		(0 "F.Cu" signal "TOP")
		(4 "In1.Cu" signal "GND")
		(6 "In2.Cu" signal "IN1")
		(8 "In3.Cu" signal "GND1")
		(10 "In4.Cu" signal "IN2")
		(12 "In5.Cu" signal "GND2")
		(14 "In6.Cu" signal "IN3")
		(16 "In7.Cu" signal "GND3")
		(18 "In8.Cu" signal "VCC")
		(20 "In9.Cu" signal "VCC1")
		(22 "In10.Cu" signal "GND4")
		(24 "In11.Cu" signal "IN4")
		(26 "In12.Cu" signal "GND5")
		(28 "In13.Cu" signal "IN5")
		(30 "In14.Cu" signal "GND6")
		(32 "In15.Cu" signal "IN6")
		(34 "In16.Cu" signal "GND7")
		(2 "B.Cu" signal "BOTTOM")
		(9 "F.Adhes" user "F.Adhesive")
		(11 "B.Adhes" user "B.Adhesive")
		(13 "F.Paste" user "Package Geometry/Pastemask Top")
		(15 "B.Paste" user "Package Geometry/Pastemask Bottom")
		(5 "F.SilkS" user "Ref Des/Silkscreen Top")
		(7 "B.SilkS" user "Ref Des/Silkscreen Bottom")
		(1 "F.Mask" user "Board Geometry/Soldermask Top")
		(3 "B.Mask" user "Board Geometry/Soldermask Bottom")
		(17 "Dwgs.User" user "User.Drawings")
		(19 "Cmts.User" user "User.Comments")
		(21 "Eco1.User" user "User.Eco1")
		(23 "Eco2.User" user "User.Eco2")
		(25 "Edge.Cuts" user "Board Geometry/Outline")
		(27 "Margin" user)
		(31 "F.CrtYd" user "Package Geometry/Place Bound Top")
		(29 "B.CrtYd" user "Package Geometry/Place Bound Bottom")
		(35 "F.Fab" user "Ref Des/Assembly Top")
		(33 "B.Fab" user "Ref Des/Assembly Bottom")
	)
	(footprint ""
		(layer "B.Cu")
		(at 434.00472 -44.1325 -90)
		(property "Reference" "R4679"
			(at 0 0 90)
			(layer "B.SilkS")
			(hide yes)
			(effects
				(font
					(size 1.27 1.27)
				)
				(justify mirror)
			)
		)
		(property "Value" ""
			(at 0 0 90)
			(layer "B.Fab")
			(effects
				(font
					(size 1.27 1.27)
				)
				(justify mirror)
			)
		)
		(duplicate_pad_numbers_are_jumpers no)
		(fp_line
			(start -0.7874 0.4064)
			(end 0.7874 0.4064)
			(stroke
				(width 0.1524)
				(type default)
			)
			(layer "B.SilkS")
		)
		(fp_line
			(start 0.7874 0.4064)
			(end 0.7874 -0.4064)
			(stroke
				(width 0.1524)
				(type default)
			)
			(layer "B.SilkS")
		)
		(fp_line
			(start -0.7874 -0.4064)
			(end -0.7874 0.4064)
			(stroke
				(width 0.1524)
				(type default)
			)
			(layer "B.SilkS")
		)
		(fp_line
			(start 0.7874 -0.4064)
			(end -0.7874 -0.4064)
			(stroke
				(width 0.1524)
				(type default)
			)
			(layer "B.SilkS")
		)
		(fp_line
			(start -0.67945 0.3048)
			(end -0.120396 0.3048)
			(stroke
				(width 0.1)
				(type default)
			)
			(layer "B.Fab")
		)
		(fp_line
			(start -0.120396 0.3048)
			(end -0.120396 0.2794)
			(stroke
				(width 0.1)
				(type default)
			)
			(layer "B.Fab")
		)
		(fp_line
			(start 0.12065 0.3048)
			(end 0.67945 0.3048)
			(stroke
				(width 0.1)
				(type default)
			)
			(layer "B.Fab")
		)
		(fp_line
			(start 0.67945 0.3048)
			(end 0.67945 -0.305054)
			(stroke
				(width 0.1)
				(type default)
			)
			(layer "B.Fab")
		)
		(fp_line
			(start -0.120396 0.2794)
			(end 0.12065 0.2794)
			(stroke
				(width 0.1)
				(type default)
			)
			(layer "B.Fab")
		)
		(fp_line
			(start 0.12065 0.2794)
			(end 0.12065 0.3048)
			(stroke
				(width 0.1)
				(type default)
			)
			(layer "B.Fab")
		)
		(fp_line
			(start -0.12065 -0.2794)
			(end -0.12065 -0.3048)
			(stroke
				(width 0.1)
				(type default)
			)
			(layer "B.Fab")
		)
		(fp_line
			(start 0.12065 -0.2794)
			(end -0.12065 -0.2794)
			(stroke
				(width 0.1)
				(type default)
			)
			(layer "B.Fab")
		)
		(fp_line
			(start -0.67945 -0.3048)
			(end -0.67945 0.3048)
			(stroke
				(width 0.1)
				(type default)
			)
			(layer "B.Fab")
		)
		(fp_line
			(start -0.12065 -0.3048)
			(end -0.67945 -0.3048)
			(stroke
				(width 0.1)
				(type default)
			)
			(layer "B.Fab")
		)
		(fp_line
			(start 0.12065 -0.305054)
			(end 0.12065 -0.2794)
			(stroke
				(width 0.1)
				(type default)
			)
			(layer "B.Fab")
		)
		(fp_line
			(start 0.67945 -0.305054)
			(end 0.12065 -0.305054)
			(stroke
				(width 0.1)
				(type default)
			)
			(layer "B.Fab")
		)
		(pad "1" smd circle
			(at 0.40005 0 90)
			(size 0 0)
			(layers "B.Cu" "B.Mask" "B.Paste")
			(net "P5V")
		)
		(pad "2" smd circle
			(at -0.40005 0 90)
			(size 0 0)
			(layers "B.Cu" "B.Mask" "B.Paste")
			(net "PWRGD_P5V")
		)
	)
	(footprint ""
		(layer "B.Cu")
		(at 316.55004 -193.53911 90)
		(property "Reference" "R340"
			(at 0 0 90)
			(layer "B.SilkS")
			(hide yes)
			(effects
				(font
					(size 1.27 1.27)
				)
				(justify mirror)
			)
		)
		(property "Value" ""
			(at 0 0 90)
			(layer "B.Fab")
			(effects
				(font
					(size 1.27 1.27)
				)
				(justify mirror)
			)
		)
		(duplicate_pad_numbers_are_jumpers no)
		(fp_line
			(start 0.7874 -0.4064)
			(end -0.7874 -0.4064)
			(stroke
				(width 0.1524)
				(type default)
			)
			(layer "B.SilkS")
		)
		(fp_line
			(start -0.7874 -0.4064)
			(end -0.7874 0.4064)
			(stroke
				(width 0.1524)
				(type default)
			)
			(layer "B.SilkS")
		)
		(fp_line
			(start 0.7874 0.4064)
			(end 0.7874 -0.4064)
			(stroke
				(width 0.1524)
				(type default)
			)
			(layer "B.SilkS")
		)
		(fp_line
			(start -0.7874 0.4064)
			(end 0.7874 0.4064)
			(stroke
				(width 0.1524)
				(type default)
			)
			(layer "B.SilkS")
		)
		(fp_line
			(start 0.67945 -0.305054)
			(end 0.12065 -0.305054)
			(stroke
				(width 0.1)
				(type default)
			)
			(layer "B.Fab")
		)
		(fp_line
			(start 0.12065 -0.305054)
			(end 0.12065 -0.2794)
			(stroke
				(width 0.1)
				(type default)
			)
			(layer "B.Fab")
		)
		(fp_line
			(start -0.12065 -0.3048)
			(end -0.67945 -0.3048)
			(stroke
				(width 0.1)
				(type default)
			)
			(layer "B.Fab")
		)
		(fp_line
			(start -0.67945 -0.3048)
			(end -0.67945 0.3048)
			(stroke
				(width 0.1)
				(type default)
			)
			(layer "B.Fab")
		)
		(fp_line
			(start 0.12065 -0.2794)
			(end -0.12065 -0.2794)
			(stroke
				(width 0.1)
				(type default)
			)
			(layer "B.Fab")
		)
		(fp_line
			(start -0.12065 -0.2794)
			(end -0.12065 -0.3048)
			(stroke
				(width 0.1)
				(type default)
			)
			(layer "B.Fab")
		)
		(fp_line
			(start 0.12065 0.2794)
			(end 0.12065 0.3048)
			(stroke
				(width 0.1)
				(type default)
			)
			(layer "B.Fab")
		)
		(fp_line
			(start -0.120396 0.2794)
			(end 0.12065 0.2794)
			(stroke
				(width 0.1)
				(type default)
			)
			(layer "B.Fab")
		)
		(fp_line
			(start 0.67945 0.3048)
			(end 0.67945 -0.305054)
			(stroke
				(width 0.1)
				(type default)
			)
			(layer "B.Fab")
		)
		(fp_line
			(start 0.12065 0.3048)
			(end 0.67945 0.3048)
			(stroke
				(width 0.1)
				(type default)
			)
			(layer "B.Fab")
		)
		(fp_line
			(start -0.120396 0.3048)
			(end -0.120396 0.2794)
			(stroke
				(width 0.1)
				(type default)
			)
			(layer "B.Fab")
		)
		(fp_line
			(start -0.67945 0.3048)
			(end -0.120396 0.3048)
			(stroke
				(width 0.1)
				(type default)
			)
			(layer "B.Fab")
		)
		(pad "1" smd circle
			(at 0.40005 0 270)
			(size 0 0)
			(layers "B.Cu" "B.Mask" "B.Paste")
			(net "H_CPU0_ERR1_LVC1_R_N")
		)
		(pad "2" smd circle
			(at -0.40005 0 270)
			(size 0 0)
			(layers "B.Cu" "B.Mask" "B.Paste")
			(net "H_CPU_ERR1_LVC1_R_N")
		)
	)
)
